# T6G (Grand Teton) — schematic netlist excerpt (pin names and nets, part order shuffled) for the footprints in the layout excerpt that follows; sources: Cadence DE-HDL packaged netlist, KiCad conversion of 04192023_DAF0TMB3IC0_F0TG_MB_C_brd_V02_OCP.brd

J19  SCONN288_DDR506112002KQ  IO  pkg DDR288S_1-1VXC  page 89
  VIN_BULK0  = P12V_MEM_CPU0
  RFU0  = NC
  VIN_MGMT  = P3V3_AUX
  HSCL  = I3C_SPD_DDRD_CPU0_SCL
  HSDA  = I3C_SPD_DDRD_CPU0_SDA
  VSS0  = GND
  DQ0_A  = M_D_CPU0_SA_DQ<0>
  VSS1  = GND
  DQ1_A  = M_D_CPU0_SA_DQ<1>
  VSS2  = GND
  DQS0_A_T  = M_D_CPU0_SA_DQS_DP<0>
  DQS0_A_C  = M_D_CPU0_SA_DQS_DN<0>
  VSS3  = GND
  DQ4_A  = M_D_CPU0_SA_DQ<4>
  VSS4  = GND
  DQ5_A  = M_D_CPU0_SA_DQ<5>
  VSS5  = GND
  DQ8_A  = M_D_CPU0_SA_DQ<8>
  VSS6  = GND
  DQ9_A  = M_D_CPU0_SA_DQ<9>
  VSS7  = GND
  DQS1_A_T  = M_D_CPU0_SA_DQS_DP<1>
  DQS1_A_C  = M_D_CPU0_SA_DQS_DN<1>
  VSS8  = GND
  DQ12_A  = M_D_CPU0_SA_DQ<12>
  VSS9  = GND
  DQ13_A  = M_D_CPU0_SA_DQ<13>
  VSS10  = GND
  DQ16_A  = M_D_CPU0_SA_DQ<16>
  VSS11  = GND
  DQ17_A  = M_D_CPU0_SA_DQ<17>
  VSS12  = GND
  DQS2_A_T  = M_D_CPU0_SA_DQS_DP<2>
  DQS2_A_C  = M_D_CPU0_SA_DQS_DN<2>
  VSS13  = GND
  DQ20_A  = M_D_CPU0_SA_DQ<20>
  VSS14  = GND
  DQ21_A  = M_D_CPU0_SA_DQ<21>
  VSS15  = GND
  DQ24_A  = M_D_CPU0_SA_DQ<24>
  VSS16  = GND
  DQ25_A  = M_D_CPU0_SA_DQ<25>
  VSS17  = GND
  DQS3_A_T  = M_D_CPU0_SA_DQS_DP<3>
  DQS3_A_C  = M_D_CPU0_SA_DQS_DN<3>
  VSS18  = GND
  DQ28_A  = M_D_CPU0_SA_DQ<28>
  VSS19  = GND
  DQ29_A  = M_D_CPU0_SA_DQ<29>
  VSS20  = GND
  CB0_A  = M_D_CPU0_SA_CB<0>
  VSS21  = GND
  CB1_A  = M_D_CPU0_SA_CB<1>
  VSS22  = GND
  DQS4_A_T  = M_D_CPU0_SA_DQS_DP<4>
  DQS4_A_C  = M_D_CPU0_SA_DQS_DN<4>
  VSS23  = GND
  CB4_A  = M_D_CPU0_SA_CB<4>
  VSS24  = GND
  CB5_A  = M_D_CPU0_SA_CB<5>
  VSS25  = GND
  ALERT_N  = M_D_CPU0_ALERT_N
  VSS26  = GND
  CS0_A_N  = M_D_CPU0_SA_CS_N<0>
  VSS27  = GND
  CA0_A  = M_D_CPU0_SA_CA<0>
  VSS28  = GND
  CA2_A  = M_D_CPU0_SA_CA<2>
  VSS29  = GND
  CA4_A  = M_D_CPU0_SA_CA<4>
  VSS30  = GND
  CA6_A  = M_D_CPU0_SA_CA<6>
  VSS31  = GND
  PAR_A  = M_D_CPU0_SA_PAR
  VSS32  = GND
  CA0_B  = M_D_CPU0_SB_CA<0>
  VSS33  = GND
  CA2_B  = M_D_CPU0_SB_CA<2>
  VSS34  = GND
  CA4_B  = M_D_CPU0_SB_CA<4>
  VSS35  = GND
  CA6_B  = M_D_CPU0_SB_CA<6>
  VSS36  = GND
  CS0_B_N  = M_D_CPU0_SB_CS_N<0>
  VSS37  = GND
  \lbd||rsp_a_n\  = M_D_CPU0_SA_RSP<0>
  \lbs||rsp_b_n\  = M_D_CPU0_SB_RSP<0>
  VSS38  = GND
  CB4_B  = M_D_CPU0_SB_CB<4>
  VSS39  = GND
  CB5_B  = M_D_CPU0_SB_CB<5>
  VSS40  = GND
  \dqs9_b_t||tdqs9_b_t||dbi4_b_n\  = M_D_CPU0_SB_DQS_DP<9>
  \dqs9_b_c||tdqs9_b_c\  = M_D_CPU0_SB_DQS_DN<9>
  VSS41  = GND
  CB0_B  = M_D_CPU0_SB_CB<0>
  VSS42  = GND
  CB1_B  = M_D_CPU0_SB_CB<1>
  VSS43  = GND
  DQ0_B  = M_D_CPU0_SB_DQ<0>
  VSS44  = GND
  DQ1_B  = M_D_CPU0_SB_DQ<1>
  VSS45  = GND
  DQS0_B_T  = M_D_CPU0_SB_DQS_DP<0>
  DQS0_B_C  = M_D_CPU0_SB_DQS_DN<0>
  VSS46  = GND
  DQ4_B  = M_D_CPU0_SB_DQ<4>
  VSS47  = GND
  DQ5_B  = M_D_CPU0_SB_DQ<5>
  VSS48  = GND
  DQ8_B  = M_D_CPU0_SB_DQ<8>
  VSS49  = GND
  DQ9_B  = M_D_CPU0_SB_DQ<9>
  VSS50  = GND
  DQS1_B_T  = M_D_CPU0_SB_DQS_DP<1>
  DQS1_B_C  = M_D_CPU0_SB_DQS_DN<1>
  VSS51  = GND
  DQ12_B  = M_D_CPU0_SB_DQ<12>
  VSS52  = GND
  DQ13_B  = M_D_CPU0_SB_DQ<13>
  VSS53  = GND
  DQ16_B  = M_D_CPU0_SB_DQ<16>
  VSS54  = GND
  DQ17_B  = M_D_CPU0_SB_DQ<17>
  VSS55  = GND
  DQS2_B_T  = M_D_CPU0_SB_DQS_DP<2>
  DQS2_B_C  = M_D_CPU0_SB_DQS_DN<2>
  VSS56  = GND
  DQ20_B  = M_D_CPU0_SB_DQ<20>
  VSS57  = GND
  DQ21_B  = M_D_CPU0_SB_DQ<21>
  VSS58  = GND
  DQ24_B  = M_D_CPU0_SB_DQ<24>
  VSS59  = GND
  DQ25_B  = M_D_CPU0_SB_DQ<25>
  VSS60  = GND
  DQS3_B_T  = M_D_CPU0_SB_DQS_DP<3>
  DQS3_B_C  = M_D_CPU0_SB_DQS_DN<3>
  VSS61  = GND
  DQ28_B  = M_D_CPU0_SB_DQ<28>
  VSS62  = GND
  DQ29_B  = M_D_CPU0_SB_DQ<29>
  VSS63  = GND
  RFU1  = NC
  VIN_BULK1  = P12V_MEM_CPU0
  VIN_BULK2  = P12V_MEM_CPU0
  \pwr_good||fail_n\  = PWRGD_CHD_CPU0_DIMM
  HAS  = PD_CHD_CPU0_DIMM_SAA
  RFU2  = NC
  RFU3  = NC
  VSS64  = GND
  DQ2_A  = M_D_CPU0_SA_DQ<2>
  VSS65  = GND
  DQ3_A  = M_D_CPU0_SA_DQ<3>
  VSS66  = GND
  \dqs5_a_c||tdqs5_a_c||dqs5_a_t||tdqs5_a_t\  = M_D_CPU0_SA_DQS_DN<5>
  \dqs5_a_t||tdqs5_a_t\  = M_D_CPU0_SA_DQS_DP<5>
  VSS67  = GND
  DQ6_A  = M_D_CPU0_SA_DQ<6>
  VSS68  = GND
  DQ7_A  = M_D_CPU0_SA_DQ<7>
  VSS69  = GND
  DQ10_A  = M_D_CPU0_SA_DQ<10>
  VSS70  = GND
  DQ11_A  = M_D_CPU0_SA_DQ<11>
  VSS71  = GND
  \dqs6_a_c||tdqs6_a_c||dqs6_a_t||tdqs6_a_t\  = M_D_CPU0_SA_DQS_DN<6>
  \dqs6_a_t||tdqs6_a_t\  = M_D_CPU0_SA_DQS_DP<6>
  VSS72  = GND
  DQ14_A  = M_D_CPU0_SA_DQ<14>
  VSS73  = GND
  DQ15_A  = M_D_CPU0_SA_DQ<15>
  VSS74  = GND
  DQ18_A  = M_D_CPU0_SA_DQ<18>
  VSS75  = GND
  DQ19_A  = M_D_CPU0_SA_DQ<19>
  VSS76  = GND
  \dqs7_a_c||tdqs7_a_c\  = M_D_CPU0_SA_DQS_DN<7>
  \dqs7_a_t||tdqs7_a_t\  = M_D_CPU0_SA_DQS_DP<7>
  VSS77  = GND
  DQ22_A  = M_D_CPU0_SA_DQ<22>
  VSS78  = GND
  DQ23_A  = M_D_CPU0_SA_DQ<23>
  VSS79  = GND
  DQ26_A  = M_D_CPU0_SA_DQ<26>
  VSS80  = GND
  DQ27_A  = M_D_CPU0_SA_DQ<27>
  VSS81  = GND
  \dqs8_a_c||tdqs8_a_c\  = M_D_CPU0_SA_DQS_DN<8>
  \dqs8_a_t||tdqs8_a_t\  = M_D_CPU0_SA_DQS_DP<8>
  VSS82  = GND
  DQ30_A  = M_D_CPU0_SA_DQ<30>
  VSS83  = GND
  DQ31_A  = M_D_CPU0_SA_DQ<31>
  VSS84  = GND
  CB2_A  = M_D_CPU0_SA_CB<2>
  VSS85  = GND
  CB3_A  = M_D_CPU0_SA_CB<3>
  VSS86  = GND
  \dqs9_a_c||tdqs9_a_c\  = M_D_CPU0_SA_DQS_DN<9>
  \dqs9_a_t||tdqs9_a_t\  = M_D_CPU0_SA_DQS_DP<9>
  VSS87  = GND
  CB6_A  = M_D_CPU0_SA_CB<6>
  VSS88  = GND
  CB7_A  = M_D_CPU0_SA_CB<7>
  VSS89  = GND
  RESET_N  = M_D_CPU0_RESET_N
  VSS90  = GND
  CS1_A_N  = M_D_CPU0_SA_CS_N<1>
  VSS91  = GND
  CA1_A  = M_D_CPU0_SA_CA<1>
  VSS92  = GND
  CA3_A  = M_D_CPU0_SA_CA<3>
  VSS93  = GND
  CA5_A  = M_D_CPU0_SA_CA<5>
  VSS94  = GND
  CK_T  = M_D_CPU0_CLK_DP<0>
  CK_C  = M_D_CPU0_CLK_DN<0>
  VSS95  = GND
  RFU4  = NC
  CA1_B  = M_D_CPU0_SB_CA<1>
  VSS96  = GND
  CA3_B  = M_D_CPU0_SB_CA<3>
  VSS97  = GND
  CA5_B  = M_D_CPU0_SB_CA<5>
  VSS98  = GND
  PAR_B  = M_D_CPU0_SB_PAR
  VSS99  = GND
  CS1_B_N  = M_D_CPU0_SB_CS_N<1>
  VSS100  = GND
  RFU5  = NC
  RFU6  = NC
  VSS101  = GND
  CB6_B  = M_D_CPU0_SB_CB<6>
  VSS102  = GND
  CB7_B  = M_D_CPU0_SB_CB<7>
  VSS103  = GND
  DQS4_B_C  = M_D_CPU0_SB_DQS_DN<4>
  DQS4_B_T  = M_D_CPU0_SB_DQS_DP<4>
  VSS104  = GND
  CB2_B  = M_D_CPU0_SB_CB<2>
  VSS105  = GND
  CB3_B  = M_D_CPU0_SB_CB<3>
  VSS106  = GND
  DQ2_B  = M_D_CPU0_SB_DQ<2>
  VSS107  = GND
  DQ3_B  = M_D_CPU0_SB_DQ<3>
  VSS108  = GND
  \dqs5_b_c||tdqs5_b_c\  = M_D_CPU0_SB_DQS_DN<5>
  \dqs5_b_t||tdqs5_b_t\  = M_D_CPU0_SB_DQS_DP<5>
  VSS109  = GND
  DQ6_B  = M_D_CPU0_SB_DQ<6>
  VSS110  = GND
  DQ7_B  = M_D_CPU0_SB_DQ<7>
  VSS111  = GND
  DQ10_B  = M_D_CPU0_SB_DQ<10>
  VSS112  = GND
  DQ11_B  = M_D_CPU0_SB_DQ<11>
  VSS113  = GND
  \dqs6_b_c||tdqs6_b_c\  = M_D_CPU0_SB_DQS_DN<6>
  \dqs6_b_t||tdqs6_b_t\  = M_D_CPU0_SB_DQS_DP<6>
  VSS114  = GND
  DQ14_B  = M_D_CPU0_SB_DQ<14>
  VSS115  = GND
  DQ15_B  = M_D_CPU0_SB_DQ<15>
  VSS116  = GND
  DQ18_B  = M_D_CPU0_SB_DQ<18>
  VSS117  = GND
  DQ19_B  = M_D_CPU0_SB_DQ<19>
  VSS118  = GND
  \dqs7_b_c||tdqs7_b_c\  = M_D_CPU0_SB_DQS_DN<7>
  \dqs7_b_t||tdqs7_b_t\  = M_D_CPU0_SB_DQS_DP<7>
  VSS119  = GND
  DQ22_B  = M_D_CPU0_SB_DQ<22>
  VSS120  = GND
  DQ23_B  = M_D_CPU0_SB_DQ<23>
  VSS121  = GND
  DQ26_B  = M_D_CPU0_SB_DQ<26>
  VSS122  = GND
  DQ27_B  = M_D_CPU0_SB_DQ<27>
  VSS123  = GND
  \dqs8_b_c||tdqs8_b_c\  = M_D_CPU0_SB_DQS_DN<8>
  \dqs8_b_t||tdqs8_b_t\  = M_D_CPU0_SB_DQS_DP<8>
  VSS124  = GND
  DQ30_B  = M_D_CPU0_SB_DQ<30>
  VSS125  = GND
  DQ31_B  = M_D_CPU0_SB_DQ<31>
  VSS126  = GND
  G1  = GND
  G2  = GND
  G3  = GND

(kicad_pcb
	(version 20260206)
	(generator "pcbnew")
	(generator_version "10.0")
	(general
		(thickness 1.6)
		(legacy_teardrops no)
	)
	(paper "A4")
	(title_block
		(title "04192023_DAF0TMB3IC0_F0TG_MB_C_brd_V02_OCP.brd")
		(comment 1 "Grand Teton / footprint 2350 of 8354 (J19), pads 277-291 of 291")
	)
	(layers
		(0 "F.Cu" signal "TOP")
		(4 "In1.Cu" signal "GND")
		(6 "In2.Cu" signal "IN1")
		(8 "In3.Cu" signal "GND1")
		(10 "In4.Cu" signal "IN2")
		(12 "In5.Cu" signal "GND2")
		(14 "In6.Cu" signal "IN3")
		(16 "In7.Cu" signal "GND3")
		(18 "In8.Cu" signal "VCC")
		(20 "In9.Cu" signal "VCC1")
		(22 "In10.Cu" signal "GND4")
		(24 "In11.Cu" signal "IN4")
		(26 "In12.Cu" signal "GND5")
		(28 "In13.Cu" signal "IN5")
		(30 "In14.Cu" signal "GND6")
		(32 "In15.Cu" signal "IN6")
		(34 "In16.Cu" signal "GND7")
		(2 "B.Cu" signal "BOTTOM")
		(9 "F.Adhes" user "F.Adhesive")
		(11 "B.Adhes" user "B.Adhesive")
		(13 "F.Paste" user "Package Geometry/Pastemask Top")
		(15 "B.Paste" user "Package Geometry/Pastemask Bottom")
		(5 "F.SilkS" user "Ref Des/Silkscreen Top")
		(7 "B.SilkS" user "Ref Des/Silkscreen Bottom")
		(1 "F.Mask" user "Board Geometry/Soldermask Top")
		(3 "B.Mask" user "Board Geometry/Soldermask Bottom")
		(17 "Dwgs.User" user "User.Drawings")
		(19 "Cmts.User" user "User.Comments")
		(21 "Eco1.User" user "User.Eco1")
		(23 "Eco2.User" user "User.Eco2")
		(25 "Edge.Cuts" user "Board Geometry/Outline")
		(27 "Margin" user)
		(31 "F.CrtYd" user "Package Geometry/Place Bound Top")
		(29 "B.CrtYd" user "Package Geometry/Place Bound Bottom")
		(35 "F.Fab" user "Ref Des/Assembly Top")
		(33 "B.Fab" user "Ref Des/Assembly Bottom")
	)
	(footprint ""
		(layer "F.Cu")
		(at 282.685998 -255.560068 180)
		(property "Reference" "J19"
			(at -2.2098 -81.984088 0)
			(unlocked yes)
			(layer "F.SilkS")
			(effects
				(font
					(size 0.7874 0.5842)
					(thickness 0.1524)
				)
			)
		)
		(property "Value" ""
			(at 0 0 180)
			(layer "F.Fab")
			(effects
				(font
					(size 1.27 1.27)
				)
			)
		)
		(duplicate_pad_numbers_are_jumpers no)
		(pad "277" smd rect
			(at 2.050034 53.975 90)
			(size 0.519938 1.4986)
			(layers "F.Cu" "F.Mask" "F.Paste")
			(net "GND")
		)
		(pad "278" smd rect
			(at 2.050034 54.824884 90)
			(size 0.519938 1.4986)
			(layers "F.Cu" "F.Mask" "F.Paste")
			(net "M_D_CPU0_SB_DQ<26>")
		)
		(pad "279" smd rect
			(at 2.050034 55.675022 90)
			(size 0.519938 1.4986)
			(layers "F.Cu" "F.Mask" "F.Paste")
			(net "GND")
		)
		(pad "280" smd rect
			(at 2.050034 56.524906 90)
			(size 0.519938 1.4986)
			(layers "F.Cu" "F.Mask" "F.Paste")
			(net "M_D_CPU0_SB_DQ<27>")
		)
		(pad "281" smd rect
			(at 2.050034 57.375044 90)
			(size 0.519938 1.4986)
			(layers "F.Cu" "F.Mask" "F.Paste")
			(net "GND")
		)
		(pad "282" smd rect
			(at 2.050034 58.224928 90)
			(size 0.519938 1.4986)
			(layers "F.Cu" "F.Mask" "F.Paste")
			(net "M_D_CPU0_SB_DQS_DN<8>")
		)
		(pad "283" smd rect
			(at 2.050034 59.075066 90)
			(size 0.519938 1.4986)
			(layers "F.Cu" "F.Mask" "F.Paste")
			(net "M_D_CPU0_SB_DQS_DP<8>")
		)
		(pad "284" smd rect
			(at 2.050034 59.92495 90)
			(size 0.519938 1.4986)
			(layers "F.Cu" "F.Mask" "F.Paste")
			(net "GND")
		)
		(pad "285" smd rect
			(at 2.050034 60.775088 90)
			(size 0.519938 1.4986)
			(layers "F.Cu" "F.Mask" "F.Paste")
			(net "M_D_CPU0_SB_DQ<30>")
		)
		(pad "286" smd rect
			(at 2.050034 61.624972 90)
			(size 0.519938 1.4986)
			(layers "F.Cu" "F.Mask" "F.Paste")
			(net "GND")
		)
		(pad "287" smd rect
			(at 2.050034 62.47511 90)
			(size 0.519938 1.4986)
			(layers "F.Cu" "F.Mask" "F.Paste")
			(net "M_D_CPU0_SB_DQ<31>")
		)
		(pad "288" smd rect
			(at 2.050034 63.324994 90)
			(size 0.519938 1.4986)
			(layers "F.Cu" "F.Mask" "F.Paste")
			(net "GND")
		)
		(pad "G1" thru_hole oval
			(at 0 -68.97497 90)
			(size 1.7272 3.4798)
			(drill oval 1.2192 2.4638)
			(layers "*.Cu" "*.Mask")
			(remove_unused_layers no)
			(net "GND")
			(clearance 0.127)
			(thermal_gap 0.127)
		)
		(pad "G2" thru_hole oval
			(at 0 3.875024 90)
			(size 1.7272 3.4798)
			(drill oval 1.2192 2.4638)
			(layers "*.Cu" "*.Mask")
			(remove_unused_layers no)
			(net "GND")
			(clearance 0.127)
			(thermal_gap 0.127)
		)
		(pad "G3" thru_hole oval
			(at 0 68.97497 90)
			(size 1.7272 3.4798)
			(drill oval 1.2192 2.4638)
			(layers "*.Cu" "*.Mask")
			(remove_unused_layers no)
			(net "GND")
			(clearance 0.127)
			(thermal_gap 0.127)
		)
	)
)
